# T6G (Grand Teton) — schematic netlist excerpt (pin names and nets, part order shuffled) for the footprints in the layout excerpt that follows; sources: Cadence DE-HDL packaged netlist, KiCad conversion of 04192023_DAF0TMB3IC0_F0TG_MB_C_brd_V02_OCP.brd

R2910  Q_RES  100K 1% EMPTY  pkg 0402LF  page 128 : A = P3V3_AUX ; B = FM_SWB_PWR_EN_R
PC566_5  Q_CAP  0.1UF 25V 10% X7R  pkg 0402  page 196 : A = PVDDCR_CPU0_P0_VCCS ; B = GND

(kicad_pcb
	(version 20260206)
	(generator "pcbnew")
	(generator_version "10.0")
	(general
		(thickness 1.6)
		(legacy_teardrops no)
	)
	(paper "A4")
	(title_block
		(title "04192023_DAF0TMB3IC0_F0TG_MB_C_brd_V02_OCP.brd")
		(comment 1 "Grand Teton / footprints 2635-2636 of 8354")
	)
	(layers
		(0 "F.Cu" signal "TOP")
		(4 "In1.Cu" signal "GND")
		(6 "In2.Cu" signal "IN1")
		(8 "In3.Cu" signal "GND1")
		(10 "In4.Cu" signal "IN2")
		(12 "In5.Cu" signal "GND2")
		(14 "In6.Cu" signal "IN3")
		(16 "In7.Cu" signal "GND3")
		(18 "In8.Cu" signal "VCC")
		(20 "In9.Cu" signal "VCC1")
		(22 "In10.Cu" signal "GND4")
		(24 "In11.Cu" signal "IN4")
		(26 "In12.Cu" signal "GND5")
		(28 "In13.Cu" signal "IN5")
		(30 "In14.Cu" signal "GND6")
		(32 "In15.Cu" signal "IN6")
		(34 "In16.Cu" signal "GND7")
		(2 "B.Cu" signal "BOTTOM")
		(9 "F.Adhes" user "F.Adhesive")
		(11 "B.Adhes" user "B.Adhesive")
		(13 "F.Paste" user "Package Geometry/Pastemask Top")
		(15 "B.Paste" user "Package Geometry/Pastemask Bottom")
		(5 "F.SilkS" user "Ref Des/Silkscreen Top")
		(7 "B.SilkS" user "Ref Des/Silkscreen Bottom")
		(1 "F.Mask" user "Board Geometry/Soldermask Top")
		(3 "B.Mask" user "Board Geometry/Soldermask Bottom")
		(17 "Dwgs.User" user "User.Drawings")
		(19 "Cmts.User" user "User.Comments")
		(21 "Eco1.User" user "User.Eco1")
		(23 "Eco2.User" user "User.Eco2")
		(25 "Edge.Cuts" user "Board Geometry/Outline")
		(27 "Margin" user)
		(31 "F.CrtYd" user "Package Geometry/Place Bound Top")
		(29 "B.CrtYd" user "Package Geometry/Place Bound Bottom")
		(35 "F.Fab" user "Ref Des/Assembly Top")
		(33 "B.Fab" user "Ref Des/Assembly Bottom")
	)
	(footprint ""
		(layer "F.Cu")
		(at 358.727502 -164.638482 -90)
		(property "Reference" "PC566_5"
			(at 0 0 270)
			(layer "F.SilkS")
			(hide yes)
			(effects
				(font
					(size 1.27 1.27)
				)
			)
		)
		(property "Value" ""
			(at 0 0 270)
			(layer "F.Fab")
			(effects
				(font
					(size 1.27 1.27)
				)
			)
		)
		(duplicate_pad_numbers_are_jumpers no)
		(fp_line
			(start -0.7874 0.4064)
			(end -0.7874 -0.4064)
			(stroke
				(width 0.1524)
				(type default)
			)
			(layer "F.SilkS")
		)
		(fp_line
			(start 0.7874 0.4064)
			(end -0.7874 0.4064)
			(stroke
				(width 0.1524)
				(type default)
			)
			(layer "F.SilkS")
		)
		(fp_line
			(start -0.7874 -0.4064)
			(end 0.7874 -0.4064)
			(stroke
				(width 0.1524)
				(type default)
			)
			(layer "F.SilkS")
		)
		(fp_line
			(start 0.7874 -0.4064)
			(end 0.7874 0.4064)
			(stroke
				(width 0.1524)
				(type default)
			)
			(layer "F.SilkS")
		)
		(fp_line
			(start -0.67945 0.3048)
			(end -0.67945 -0.305054)
			(stroke
				(width 0.1)
				(type default)
			)
			(layer "F.Fab")
		)
		(fp_line
			(start -0.12065 0.3048)
			(end -0.67945 0.3048)
			(stroke
				(width 0.1)
				(type default)
			)
			(layer "F.Fab")
		)
		(fp_line
			(start 0.120396 0.3048)
			(end 0.120396 0.2794)
			(stroke
				(width 0.1)
				(type default)
			)
			(layer "F.Fab")
		)
		(fp_line
			(start 0.67945 0.3048)
			(end 0.120396 0.3048)
			(stroke
				(width 0.1)
				(type default)
			)
			(layer "F.Fab")
		)
		(fp_line
			(start -0.12065 0.2794)
			(end -0.12065 0.3048)
			(stroke
				(width 0.1)
				(type default)
			)
			(layer "F.Fab")
		)
		(fp_line
			(start 0.120396 0.2794)
			(end -0.12065 0.2794)
			(stroke
				(width 0.1)
				(type default)
			)
			(layer "F.Fab")
		)
		(fp_line
			(start -0.12065 -0.2794)
			(end 0.12065 -0.2794)
			(stroke
				(width 0.1)
				(type default)
			)
			(layer "F.Fab")
		)
		(fp_line
			(start 0.12065 -0.2794)
			(end 0.12065 -0.3048)
			(stroke
				(width 0.1)
				(type default)
			)
			(layer "F.Fab")
		)
		(fp_line
			(start 0.12065 -0.3048)
			(end 0.67945 -0.3048)
			(stroke
				(width 0.1)
				(type default)
			)
			(layer "F.Fab")
		)
		(fp_line
			(start 0.67945 -0.3048)
			(end 0.67945 0.3048)
			(stroke
				(width 0.1)
				(type default)
			)
			(layer "F.Fab")
		)
		(fp_line
			(start -0.67945 -0.305054)
			(end -0.12065 -0.305054)
			(stroke
				(width 0.1)
				(type default)
			)
			(layer "F.Fab")
		)
		(fp_line
			(start -0.12065 -0.305054)
			(end -0.12065 -0.2794)
			(stroke
				(width 0.1)
				(type default)
			)
			(layer "F.Fab")
		)
		(pad "1" smd circle
			(at -0.40005 0 270)
			(size 0 0)
			(layers "F.Cu" "F.Mask" "F.Paste")
			(net "PVDDCR_CPU0_P0_VCCS")
		)
		(pad "2" smd circle
			(at 0.40005 0 270)
			(size 0 0)
			(layers "F.Cu" "F.Mask" "F.Paste")
			(net "GND")
		)
	)
	(footprint ""
		(layer "F.Cu")
		(at 38.0746 -437.226964 -90)
		(property "Reference" "R2910"
			(at 0 0 270)
			(layer "F.SilkS")
			(hide yes)
			(effects
				(font
					(size 1.27 1.27)
				)
			)
		)
		(property "Value" ""
			(at 0 0 270)
			(layer "F.Fab")
			(effects
				(font
					(size 1.27 1.27)
				)
			)
		)
		(duplicate_pad_numbers_are_jumpers no)
		(fp_line
			(start -0.7874 0.4064)
			(end -0.7874 -0.4064)
			(stroke
				(width 0.1524)
				(type default)
			)
			(layer "F.SilkS")
		)
		(fp_line
			(start 0.7874 0.4064)
			(end -0.7874 0.4064)
			(stroke
				(width 0.1524)
				(type default)
			)
			(layer "F.SilkS")
		)
		(fp_line
			(start -0.7874 -0.4064)
			(end 0.7874 -0.4064)
			(stroke
				(width 0.1524)
				(type default)
			)
			(layer "F.SilkS")
		)
		(fp_line
			(start 0.7874 -0.4064)
			(end 0.7874 0.4064)
			(stroke
				(width 0.1524)
				(type default)
			)
			(layer "F.SilkS")
		)
		(fp_line
			(start -0.67945 0.3048)
			(end -0.67945 -0.305054)
			(stroke
				(width 0.1)
				(type default)
			)
			(layer "F.Fab")
		)
		(fp_line
			(start -0.12065 0.3048)
			(end -0.67945 0.3048)
			(stroke
				(width 0.1)
				(type default)
			)
			(layer "F.Fab")
		)
		(fp_line
			(start 0.120396 0.3048)
			(end 0.120396 0.2794)
			(stroke
				(width 0.1)
				(type default)
			)
			(layer "F.Fab")
		)
		(fp_line
			(start 0.67945 0.3048)
			(end 0.120396 0.3048)
			(stroke
				(width 0.1)
				(type default)
			)
			(layer "F.Fab")
		)
		(fp_line
			(start -0.12065 0.2794)
			(end -0.12065 0.3048)
			(stroke
				(width 0.1)
				(type default)
			)
			(layer "F.Fab")
		)
		(fp_line
			(start 0.120396 0.2794)
			(end -0.12065 0.2794)
			(stroke
				(width 0.1)
				(type default)
			)
			(layer "F.Fab")
		)
		(fp_line
			(start -0.12065 -0.2794)
			(end 0.12065 -0.2794)
			(stroke
				(width 0.1)
				(type default)
			)
			(layer "F.Fab")
		)
		(fp_line
			(start 0.12065 -0.2794)
			(end 0.12065 -0.3048)
			(stroke
				(width 0.1)
				(type default)
			)
			(layer "F.Fab")
		)
		(fp_line
			(start 0.12065 -0.3048)
			(end 0.67945 -0.3048)
			(stroke
				(width 0.1)
				(type default)
			)
			(layer "F.Fab")
		)
		(fp_line
			(start 0.67945 -0.3048)
			(end 0.67945 0.3048)
			(stroke
				(width 0.1)
				(type default)
			)
			(layer "F.Fab")
		)
		(fp_line
			(start -0.67945 -0.305054)
			(end -0.12065 -0.305054)
			(stroke
				(width 0.1)
				(type default)
			)
			(layer "F.Fab")
		)
		(fp_line
			(start -0.12065 -0.305054)
			(end -0.12065 -0.2794)
			(stroke
				(width 0.1)
				(type default)
			)
			(layer "F.Fab")
		)
		(pad "1" smd circle
			(at -0.40005 0 270)
			(size 0 0)
			(layers "F.Cu" "F.Mask" "F.Paste")
			(net "P3V3_AUX")
		)
		(pad "2" smd circle
			(at 0.40005 0 270)
			(size 0 0)
			(layers "F.Cu" "F.Mask" "F.Paste")
			(net "FM_SWB_PWR_EN_R")
		)
	)
)
